FILE_TYPE = CONNECTIVITY;
{Allegro Design Entry HDL 17.2-2016 S081 (4005846) 1/11/2022}
"PAGE_NUMBER" = 60;
0"NC";
1"P5E_CPU1_PE1_TX_DP<15:0>";
2"P5E_CPU1_PE1_TX_DN<15:0>";
3"P5E_CPU1_PE1_RX_DP<15:0>";
4"P5E_CPU1_PE1_RX_DN<15:0>";
5"P5E_CPU1_PE0_TX_DP<15:0>";
6"P5E_CPU1_PE0_TX_DN<15:0>";
7"P5E_CPU1_PE0_RX_DP<15:0>";
8"P5E_CPU1_PE0_RX_DN<15:0>";
9"P5E_CPU1_PE0_RX_DN<15>";
10"P5E_CPU1_PE0_RX_DN<14>";
11"P5E_CPU1_PE0_RX_DN<13>";
12"P5E_CPU1_PE0_RX_DN<12>";
13"P5E_CPU1_PE0_RX_DN<11>";
14"P5E_CPU1_PE0_RX_DN<10>";
15"P5E_CPU1_PE0_RX_DN<9>";
16"P5E_CPU1_PE0_RX_DN<8>";
17"P5E_CPU1_PE0_RX_DN<7>";
18"P5E_CPU1_PE0_RX_DN<6>";
19"P5E_CPU1_PE0_RX_DN<5>";
20"P5E_CPU1_PE0_RX_DN<4>";
21"P5E_CPU1_PE0_RX_DN<3>";
22"P5E_CPU1_PE0_RX_DN<2>";
23"P5E_CPU1_PE0_RX_DN<1>";
24"P5E_CPU1_PE0_RX_DN<0>";
25"P5E_CPU1_PE0_RX_DP<15>";
26"P5E_CPU1_PE0_RX_DP<14>";
27"P5E_CPU1_PE0_RX_DP<13>";
28"P5E_CPU1_PE0_RX_DP<12>";
29"P5E_CPU1_PE0_RX_DP<11>";
30"P5E_CPU1_PE0_RX_DP<10>";
31"P5E_CPU1_PE0_RX_DP<9>";
32"P5E_CPU1_PE0_RX_DP<8>";
33"P5E_CPU1_PE0_RX_DP<7>";
34"P5E_CPU1_PE0_RX_DP<6>";
35"P5E_CPU1_PE0_RX_DP<5>";
36"P5E_CPU1_PE0_RX_DP<4>";
37"P5E_CPU1_PE0_RX_DP<3>";
38"P5E_CPU1_PE0_RX_DP<2>";
39"P5E_CPU1_PE0_RX_DP<1>";
40"P5E_CPU1_PE0_RX_DP<0>";
41"P5E_CPU1_PE0_TX_DN<15>";
42"P5E_CPU1_PE0_TX_DN<14>";
43"P5E_CPU1_PE0_TX_DN<13>";
44"P5E_CPU1_PE0_TX_DN<12>";
45"P5E_CPU1_PE0_TX_DN<11>";
46"P5E_CPU1_PE0_TX_DN<10>";
47"P5E_CPU1_PE0_TX_DN<9>";
48"P5E_CPU1_PE0_TX_DN<8>";
49"P5E_CPU1_PE0_TX_DN<7>";
50"P5E_CPU1_PE0_TX_DN<6>";
51"P5E_CPU1_PE0_TX_DN<5>";
52"P5E_CPU1_PE0_TX_DN<4>";
53"P5E_CPU1_PE0_TX_DN<3>";
54"P5E_CPU1_PE0_TX_DN<2>";
55"P5E_CPU1_PE0_TX_DN<1>";
56"P5E_CPU1_PE0_TX_DN<0>";
57"P5E_CPU1_PE0_TX_DP<15>";
58"P5E_CPU1_PE0_TX_DP<14>";
59"P5E_CPU1_PE0_TX_DP<13>";
60"P5E_CPU1_PE0_TX_DP<12>";
61"P5E_CPU1_PE0_TX_DP<11>";
62"P5E_CPU1_PE0_TX_DP<10>";
63"P5E_CPU1_PE0_TX_DP<9>";
64"P5E_CPU1_PE0_TX_DP<8>";
65"P5E_CPU1_PE0_TX_DP<7>";
66"P5E_CPU1_PE0_TX_DP<6>";
67"P5E_CPU1_PE0_TX_DP<5>";
68"P5E_CPU1_PE0_TX_DP<4>";
69"P5E_CPU1_PE0_TX_DP<3>";
70"P5E_CPU1_PE0_TX_DP<2>";
71"P5E_CPU1_PE0_TX_DP<1>";
72"P5E_CPU1_PE0_TX_DP<0>";
73"P5E_CPU1_PE1_RX_DN<15>";
74"P5E_CPU1_PE1_RX_DN<14>";
75"P5E_CPU1_PE1_RX_DN<13>";
76"P5E_CPU1_PE1_RX_DN<12>";
77"P5E_CPU1_PE1_RX_DN<11>";
78"P5E_CPU1_PE1_RX_DN<10>";
79"P5E_CPU1_PE1_RX_DN<9>";
80"P5E_CPU1_PE1_RX_DN<8>";
81"P5E_CPU1_PE1_RX_DN<7>";
82"P5E_CPU1_PE1_RX_DN<6>";
83"P5E_CPU1_PE1_RX_DN<5>";
84"P5E_CPU1_PE1_RX_DN<4>";
85"P5E_CPU1_PE1_RX_DN<3>";
86"P5E_CPU1_PE1_RX_DN<2>";
87"P5E_CPU1_PE1_RX_DN<1>";
88"P5E_CPU1_PE1_RX_DN<0>";
89"P5E_CPU1_PE1_RX_DP<15>";
90"P5E_CPU1_PE1_RX_DP<14>";
91"P5E_CPU1_PE1_RX_DP<13>";
92"P5E_CPU1_PE1_RX_DP<12>";
93"P5E_CPU1_PE1_RX_DP<11>";
94"P5E_CPU1_PE1_RX_DP<10>";
95"P5E_CPU1_PE1_RX_DP<9>";
96"P5E_CPU1_PE1_RX_DP<8>";
97"P5E_CPU1_PE1_RX_DP<7>";
98"P5E_CPU1_PE1_RX_DP<6>";
99"P5E_CPU1_PE1_RX_DP<5>";
100"P5E_CPU1_PE1_RX_DP<4>";
101"P5E_CPU1_PE1_RX_DP<3>";
102"P5E_CPU1_PE1_RX_DP<2>";
103"P5E_CPU1_PE1_RX_DP<1>";
104"P5E_CPU1_PE1_RX_DP<0>";
105"P5E_CPU1_PE1_TX_DN<15>";
106"P5E_CPU1_PE1_TX_DN<14>";
107"P5E_CPU1_PE1_TX_DN<13>";
108"P5E_CPU1_PE1_TX_DN<12>";
109"P5E_CPU1_PE1_TX_DN<11>";
110"P5E_CPU1_PE1_TX_DN<10>";
111"P5E_CPU1_PE1_TX_DN<9>";
112"P5E_CPU1_PE1_TX_DN<8>";
113"P5E_CPU1_PE1_TX_DN<7>";
114"P5E_CPU1_PE1_TX_DN<6>";
115"P5E_CPU1_PE1_TX_DN<5>";
116"P5E_CPU1_PE1_TX_DN<4>";
117"P5E_CPU1_PE1_TX_DN<3>";
118"P5E_CPU1_PE1_TX_DN<2>";
119"P5E_CPU1_PE1_TX_DN<1>";
120"P5E_CPU1_PE1_TX_DN<0>";
121"P5E_CPU1_PE1_TX_DP<15>";
122"P5E_CPU1_PE1_TX_DP<14>";
123"P5E_CPU1_PE1_TX_DP<13>";
124"P5E_CPU1_PE1_TX_DP<12>";
125"P5E_CPU1_PE1_TX_DP<11>";
126"P5E_CPU1_PE1_TX_DP<10>";
127"P5E_CPU1_PE1_TX_DP<9>";
128"P5E_CPU1_PE1_TX_DP<8>";
129"P5E_CPU1_PE1_TX_DP<7>";
130"P5E_CPU1_PE1_TX_DP<6>";
131"P5E_CPU1_PE1_TX_DP<5>";
132"P5E_CPU1_PE1_TX_DP<4>";
133"P5E_CPU1_PE1_TX_DP<3>";
134"P5E_CPU1_PE1_TX_DP<2>";
135"P5E_CPU1_PE1_TX_DP<1>";
136"P5E_CPU1_PE1_TX_DP<0>";
%"TAP"
"1","(-25,3950)","2","standard","I304";
;
CDS_LIB"standard"
BODY_TYPE"PLUMBING"
HDL_TAP"TRUE";
"B \NAC \NWC"7;
"S \NAC"
BN"13"27;
%"TAP"
"1","(-25,3900)","2","standard","I305";
;
CDS_LIB"standard"
BODY_TYPE"PLUMBING"
HDL_TAP"TRUE";
"B \NAC \NWC"7;
"S \NAC"
BN"12"28;
%"TAP"
"1","(-25,4050)","2","standard","I306";
;
CDS_LIB"standard"
BODY_TYPE"PLUMBING"
HDL_TAP"TRUE";
"B \NAC \NWC"7;
"S \NAC"
BN"15"25;
%"TAP"
"1","(-25,4000)","2","standard","I307";
;
CDS_LIB"standard"
BODY_TYPE"PLUMBING"
HDL_TAP"TRUE";
"B \NAC \NWC"7;
"S \NAC"
BN"14"26;
%"TAP"
"1","(-25,3850)","2","standard","I308";
;
CDS_LIB"standard"
BODY_TYPE"PLUMBING"
HDL_TAP"TRUE";
"B \NAC \NWC"7;
"S \NAC"
BN"11"29;
%"TAP"
"1","(-25,3800)","2","standard","I309";
;
CDS_LIB"standard"
BODY_TYPE"PLUMBING"
HDL_TAP"TRUE";
"B \NAC \NWC"7;
"S \NAC"
BN"10"30;
%"TAP"
"1","(-25,3700)","2","standard","I310";
;
CDS_LIB"standard"
BODY_TYPE"PLUMBING"
HDL_TAP"TRUE";
"B \NAC \NWC"7;
"S \NAC"
BN"8"32;
%"TAP"
"1","(-25,3750)","2","standard","I311";
;
CDS_LIB"standard"
BODY_TYPE"PLUMBING"
HDL_TAP"TRUE";
"B \NAC \NWC"7;
"S \NAC"
BN"9"31;
%"TAP"
"1","(-25,3650)","2","standard","I312";
;
CDS_LIB"standard"
BODY_TYPE"PLUMBING"
HDL_TAP"TRUE";
"B \NAC \NWC"7;
"S \NAC"
BN"7"33;
%"TAP"
"1","(-25,3600)","2","standard","I313";
;
CDS_LIB"standard"
BODY_TYPE"PLUMBING"
HDL_TAP"TRUE";
"B \NAC \NWC"7;
"S \NAC"
BN"6"34;
%"TAP"
"1","(-25,3550)","2","standard","I314";
;
CDS_LIB"standard"
BODY_TYPE"PLUMBING"
HDL_TAP"TRUE";
"B \NAC \NWC"7;
"S \NAC"
BN"5"35;
%"TAP"
"1","(-25,3450)","2","standard","I315";
;
CDS_LIB"standard"
BODY_TYPE"PLUMBING"
HDL_TAP"TRUE";
"B \NAC \NWC"7;
"S \NAC"
BN"3"37;
%"TAP"
"1","(-25,3500)","2","standard","I316";
;
CDS_LIB"standard"
BODY_TYPE"PLUMBING"
HDL_TAP"TRUE";
"B \NAC \NWC"7;
"S \NAC"
BN"4"36;
%"TAP"
"1","(-25,3300)","2","standard","I317";
;
CDS_LIB"standard"
BODY_TYPE"PLUMBING"
HDL_TAP"TRUE";
"B \NAC \NWC"7;
"S \NAC"
BN"0"40;
%"TAP"
"1","(-25,3400)","2","standard","I318";
;
CDS_LIB"standard"
BODY_TYPE"PLUMBING"
HDL_TAP"TRUE";
"B \NAC \NWC"7;
"S \NAC"
BN"2"38;
%"TAP"
"1","(-25,3350)","2","standard","I319";
;
CDS_LIB"standard"
BODY_TYPE"PLUMBING"
HDL_TAP"TRUE";
"B \NAC \NWC"7;
"S \NAC"
BN"1"39;
%"TAP"
"1","(-25,2500)","2","standard","I321";
;
CDS_LIB"standard"
BODY_TYPE"PLUMBING"
HDL_TAP"TRUE";
"B \NAC \NWC"8;
"S \NAC"
BN"1"23;
%"TAP"
"1","(-25,3200)","2","standard","I322";
;
CDS_LIB"standard"
BODY_TYPE"PLUMBING"
HDL_TAP"TRUE";
"B \NAC \NWC"8;
"S \NAC"
BN"15"9;
%"TAP"
"1","(-25,3150)","2","standard","I323";
;
CDS_LIB"standard"
BODY_TYPE"PLUMBING"
HDL_TAP"TRUE";
"B \NAC \NWC"8;
"S \NAC"
BN"14"10;
%"TAP"
"1","(-25,3100)","2","standard","I324";
;
CDS_LIB"standard"
BODY_TYPE"PLUMBING"
HDL_TAP"TRUE";
"B \NAC \NWC"8;
"S \NAC"
BN"13"11;
%"TAP"
"1","(-25,3050)","2","standard","I325";
;
CDS_LIB"standard"
BODY_TYPE"PLUMBING"
HDL_TAP"TRUE";
"B \NAC \NWC"8;
"S \NAC"
BN"12"12;
%"TAP"
"1","(-25,3000)","2","standard","I326";
;
CDS_LIB"standard"
BODY_TYPE"PLUMBING"
HDL_TAP"TRUE";
"B \NAC \NWC"8;
"S \NAC"
BN"11"13;
%"TAP"
"1","(-25,2950)","2","standard","I327";
;
CDS_LIB"standard"
BODY_TYPE"PLUMBING"
HDL_TAP"TRUE";
"B \NAC \NWC"8;
"S \NAC"
BN"10"14;
%"TAP"
"1","(-25,2900)","2","standard","I328";
;
CDS_LIB"standard"
BODY_TYPE"PLUMBING"
HDL_TAP"TRUE";
"B \NAC \NWC"8;
"S \NAC"
BN"9"15;
%"TAP"
"1","(-25,2850)","2","standard","I329";
;
CDS_LIB"standard"
BODY_TYPE"PLUMBING"
HDL_TAP"TRUE";
"B \NAC \NWC"8;
"S \NAC"
BN"8"16;
%"TAP"
"1","(-25,2750)","2","standard","I330";
;
CDS_LIB"standard"
BODY_TYPE"PLUMBING"
HDL_TAP"TRUE";
"B \NAC \NWC"8;
"S \NAC"
BN"6"18;
%"TAP"
"1","(-25,2800)","2","standard","I331";
;
CDS_LIB"standard"
BODY_TYPE"PLUMBING"
HDL_TAP"TRUE";
"B \NAC \NWC"8;
"S \NAC"
BN"7"17;
%"TAP"
"1","(-25,2650)","2","standard","I332";
;
CDS_LIB"standard"
BODY_TYPE"PLUMBING"
HDL_TAP"TRUE";
"B \NAC \NWC"8;
"S \NAC"
BN"4"20;
%"TAP"
"1","(-25,2700)","2","standard","I333";
;
CDS_LIB"standard"
BODY_TYPE"PLUMBING"
HDL_TAP"TRUE";
"B \NAC \NWC"8;
"S \NAC"
BN"5"19;
%"TAP"
"1","(-25,2600)","2","standard","I334";
;
CDS_LIB"standard"
BODY_TYPE"PLUMBING"
HDL_TAP"TRUE";
"B \NAC \NWC"8;
"S \NAC"
BN"3"21;
%"TAP"
"1","(-25,2550)","2","standard","I335";
;
CDS_LIB"standard"
BODY_TYPE"PLUMBING"
HDL_TAP"TRUE";
"B \NAC \NWC"8;
"S \NAC"
BN"2"22;
%"TAP"
"1","(-25,2450)","2","standard","I336";
;
CDS_LIB"standard"
BODY_TYPE"PLUMBING"
HDL_TAP"TRUE";
"B \NAC \NWC"8;
"S \NAC"
BN"0"24;
%"TAP"
"1","(-25,225)","2","standard","I338";
;
CDS_LIB"standard"
BODY_TYPE"PLUMBING"
HDL_TAP"TRUE";
"B \NAC \NWC"4;
"S \NAC"
BN"11"77;
%"TAP"
"1","(-25,175)","2","standard","I339";
;
CDS_LIB"standard"
BODY_TYPE"PLUMBING"
HDL_TAP"TRUE";
"B \NAC \NWC"4;
"S \NAC"
BN"10"78;
%"TAP"
"1","(-25,125)","2","standard","I340";
;
CDS_LIB"standard"
BODY_TYPE"PLUMBING"
HDL_TAP"TRUE";
"B \NAC \NWC"4;
"S \NAC"
BN"9"79;
%"TAP"
"1","(-25,1275)","2","standard","I341";
;
CDS_LIB"standard"
BODY_TYPE"PLUMBING"
HDL_TAP"TRUE";
"B \NAC \NWC"3;
"S \NAC"
BN"15"89;
%"TAP"
"1","(-25,1225)","2","standard","I342";
;
CDS_LIB"standard"
BODY_TYPE"PLUMBING"
HDL_TAP"TRUE";
"B \NAC \NWC"3;
"S \NAC"
BN"14"90;
%"TAP"
"1","(-25,1175)","2","standard","I343";
;
CDS_LIB"standard"
BODY_TYPE"PLUMBING"
HDL_TAP"TRUE";
"B \NAC \NWC"3;
"S \NAC"
BN"13"91;
%"TAP"
"1","(-25,1125)","2","standard","I344";
;
CDS_LIB"standard"
BODY_TYPE"PLUMBING"
HDL_TAP"TRUE";
"B \NAC \NWC"3;
"S \NAC"
BN"12"92;
%"TAP"
"1","(-25,1075)","2","standard","I345";
;
CDS_LIB"standard"
BODY_TYPE"PLUMBING"
HDL_TAP"TRUE";
"B \NAC \NWC"3;
"S \NAC"
BN"11"93;
%"TAP"
"1","(-25,1025)","2","standard","I346";
;
CDS_LIB"standard"
BODY_TYPE"PLUMBING"
HDL_TAP"TRUE";
"B \NAC \NWC"3;
"S \NAC"
BN"10"94;
%"TAP"
"1","(-25,975)","2","standard","I347";
;
CDS_LIB"standard"
BODY_TYPE"PLUMBING"
HDL_TAP"TRUE";
"B \NAC \NWC"3;
"S \NAC"
BN"9"95;
%"TAP"
"1","(-25,925)","2","standard","I348";
;
CDS_LIB"standard"
BODY_TYPE"PLUMBING"
HDL_TAP"TRUE";
"B \NAC \NWC"3;
"S \NAC"
BN"8"96;
%"TAP"
"1","(-25,825)","2","standard","I349";
;
CDS_LIB"standard"
BODY_TYPE"PLUMBING"
HDL_TAP"TRUE";
"B \NAC \NWC"3;
"S \NAC"
BN"6"98;
%"TAP"
"1","(-25,875)","2","standard","I350";
;
CDS_LIB"standard"
BODY_TYPE"PLUMBING"
HDL_TAP"TRUE";
"B \NAC \NWC"3;
"S \NAC"
BN"7"97;
%"TAP"
"1","(-25,725)","2","standard","I351";
;
CDS_LIB"standard"
BODY_TYPE"PLUMBING"
HDL_TAP"TRUE";
"B \NAC \NWC"3;
"S \NAC"
BN"4"100;
%"TAP"
"1","(-25,775)","2","standard","I352";
;
CDS_LIB"standard"
BODY_TYPE"PLUMBING"
HDL_TAP"TRUE";
"B \NAC \NWC"3;
"S \NAC"
BN"5"99;
%"TAP"
"1","(-25,675)","2","standard","I353";
;
CDS_LIB"standard"
BODY_TYPE"PLUMBING"
HDL_TAP"TRUE";
"B \NAC \NWC"3;
"S \NAC"
BN"3"101;
%"TAP"
"1","(-25,575)","2","standard","I354";
;
CDS_LIB"standard"
BODY_TYPE"PLUMBING"
HDL_TAP"TRUE";
"B \NAC \NWC"3;
"S \NAC"
BN"1"103;
%"TAP"
"1","(-25,625)","2","standard","I355";
;
CDS_LIB"standard"
BODY_TYPE"PLUMBING"
HDL_TAP"TRUE";
"B \NAC \NWC"3;
"S \NAC"
BN"2"102;
%"TAP"
"1","(-25,525)","2","standard","I356";
;
CDS_LIB"standard"
BODY_TYPE"PLUMBING"
HDL_TAP"TRUE";
"B \NAC \NWC"3;
"S \NAC"
BN"0"104;
%"TAP"
"1","(-25,425)","2","standard","I357";
;
CDS_LIB"standard"
BODY_TYPE"PLUMBING"
HDL_TAP"TRUE";
"B \NAC \NWC"4;
"S \NAC"
BN"15"73;
%"TAP"
"1","(-25,375)","2","standard","I358";
;
CDS_LIB"standard"
BODY_TYPE"PLUMBING"
HDL_TAP"TRUE";
"B \NAC \NWC"4;
"S \NAC"
BN"14"74;
%"TAP"
"1","(-25,325)","2","standard","I359";
;
CDS_LIB"standard"
BODY_TYPE"PLUMBING"
HDL_TAP"TRUE";
"B \NAC \NWC"4;
"S \NAC"
BN"13"75;
%"TAP"
"1","(-25,275)","2","standard","I360";
;
CDS_LIB"standard"
BODY_TYPE"PLUMBING"
HDL_TAP"TRUE";
"B \NAC \NWC"4;
"S \NAC"
BN"12"76;
%"TAP"
"1","(-25,75)","2","standard","I361";
;
CDS_LIB"standard"
BODY_TYPE"PLUMBING"
HDL_TAP"TRUE";
"B \NAC \NWC"4;
"S \NAC"
BN"8"80;
%"TAP"
"1","(-25,-75)","2","standard","I362";
;
CDS_LIB"standard"
BODY_TYPE"PLUMBING"
HDL_TAP"TRUE";
"B \NAC \NWC"4;
"S \NAC"
BN"5"83;
%"TAP"
"1","(-25,25)","2","standard","I363";
;
CDS_LIB"standard"
BODY_TYPE"PLUMBING"
HDL_TAP"TRUE";
"B \NAC \NWC"4;
"S \NAC"
BN"7"81;
%"TAP"
"1","(-25,-25)","2","standard","I364";
;
CDS_LIB"standard"
BODY_TYPE"PLUMBING"
HDL_TAP"TRUE";
"B \NAC \NWC"4;
"S \NAC"
BN"6"82;
%"TAP"
"1","(-25,-125)","2","standard","I365";
;
CDS_LIB"standard"
BODY_TYPE"PLUMBING"
HDL_TAP"TRUE";
"B \NAC \NWC"4;
"S \NAC"
BN"4"84;
%"TAP"
"1","(-25,-175)","2","standard","I366";
;
CDS_LIB"standard"
BODY_TYPE"PLUMBING"
HDL_TAP"TRUE";
"B \NAC \NWC"4;
"S \NAC"
BN"3"85;
%"TAP"
"1","(-25,-275)","2","standard","I367";
;
CDS_LIB"standard"
BODY_TYPE"PLUMBING"
HDL_TAP"TRUE";
"B \NAC \NWC"4;
"S \NAC"
BN"1"87;
%"TAP"
"1","(-25,-225)","2","standard","I368";
;
CDS_LIB"standard"
BODY_TYPE"PLUMBING"
HDL_TAP"TRUE";
"B \NAC \NWC"4;
"S \NAC"
BN"2"86;
%"TAP"
"1","(-25,-325)","2","standard","I369";
;
CDS_LIB"standard"
BODY_TYPE"PLUMBING"
HDL_TAP"TRUE";
"B \NAC \NWC"4;
"S \NAC"
BN"0"88;
%"TAP"
"1","(3400,-325)","0","standard","I440";
;
CDS_LIB"standard"
BODY_TYPE"PLUMBING"
HDL_TAP"TRUE";
"B \NAC \NWC"2;
"S \NAC"
BN"0"120;
%"TAP"
"1","(3400,-225)","0","standard","I441";
;
CDS_LIB"standard"
BODY_TYPE"PLUMBING"
HDL_TAP"TRUE";
"B \NAC \NWC"2;
"S \NAC"
BN"2"118;
%"TAP"
"1","(3400,-275)","0","standard","I442";
;
CDS_LIB"standard"
BODY_TYPE"PLUMBING"
HDL_TAP"TRUE";
"B \NAC \NWC"2;
"S \NAC"
BN"1"119;
%"TAP"
"1","(3400,-175)","0","standard","I443";
;
CDS_LIB"standard"
BODY_TYPE"PLUMBING"
HDL_TAP"TRUE";
"B \NAC \NWC"2;
"S \NAC"
BN"3"117;
%"TAP"
"1","(3400,-125)","0","standard","I444";
;
CDS_LIB"standard"
BODY_TYPE"PLUMBING"
HDL_TAP"TRUE";
"B \NAC \NWC"2;
"S \NAC"
BN"4"116;
%"TAP"
"1","(3400,25)","0","standard","I445";
;
CDS_LIB"standard"
BODY_TYPE"PLUMBING"
HDL_TAP"TRUE";
"B \NAC \NWC"2;
"S \NAC"
BN"7"113;
%"TAP"
"1","(3400,75)","0","standard","I446";
;
CDS_LIB"standard"
BODY_TYPE"PLUMBING"
HDL_TAP"TRUE";
"B \NAC \NWC"2;
"S \NAC"
BN"8"112;
%"TAP"
"1","(3400,175)","0","standard","I447";
;
CDS_LIB"standard"
BODY_TYPE"PLUMBING"
HDL_TAP"TRUE";
"B \NAC \NWC"2;
"S \NAC"
BN"10"110;
%"TAP"
"1","(3400,125)","0","standard","I448";
;
CDS_LIB"standard"
BODY_TYPE"PLUMBING"
HDL_TAP"TRUE";
"B \NAC \NWC"2;
"S \NAC"
BN"9"111;
%"TAP"
"1","(3400,325)","0","standard","I449";
;
CDS_LIB"standard"
BODY_TYPE"PLUMBING"
HDL_TAP"TRUE";
"B \NAC \NWC"2;
"S \NAC"
BN"13"107;
%"TAP"
"1","(3400,275)","0","standard","I450";
;
CDS_LIB"standard"
BODY_TYPE"PLUMBING"
HDL_TAP"TRUE";
"B \NAC \NWC"2;
"S \NAC"
BN"12"108;
%"TAP"
"1","(3400,225)","0","standard","I451";
;
CDS_LIB"standard"
BODY_TYPE"PLUMBING"
HDL_TAP"TRUE";
"B \NAC \NWC"2;
"S \NAC"
BN"11"109;
%"TAP"
"1","(3400,425)","0","standard","I452";
;
CDS_LIB"standard"
BODY_TYPE"PLUMBING"
HDL_TAP"TRUE";
"B \NAC \NWC"2;
"S \NAC"
BN"15"105;
%"TAP"
"1","(3400,375)","0","standard","I453";
;
CDS_LIB"standard"
BODY_TYPE"PLUMBING"
HDL_TAP"TRUE";
"B \NAC \NWC"2;
"S \NAC"
BN"14"106;
%"TAP"
"1","(3400,525)","0","standard","I454";
;
CDS_LIB"standard"
BODY_TYPE"PLUMBING"
HDL_TAP"TRUE";
"B \NAC \NWC"1;
"S \NAC"
BN"0"136;
%"TAP"
"1","(3400,575)","0","standard","I455";
;
CDS_LIB"standard"
BODY_TYPE"PLUMBING"
HDL_TAP"TRUE";
"B \NAC \NWC"1;
"S \NAC"
BN"1"135;
%"TAP"
"1","(3400,675)","0","standard","I456";
;
CDS_LIB"standard"
BODY_TYPE"PLUMBING"
HDL_TAP"TRUE";
"B \NAC \NWC"1;
"S \NAC"
BN"3"133;
%"TAP"
"1","(3400,625)","0","standard","I457";
;
CDS_LIB"standard"
BODY_TYPE"PLUMBING"
HDL_TAP"TRUE";
"B \NAC \NWC"1;
"S \NAC"
BN"2"134;
%"TAP"
"1","(3400,825)","0","standard","I458";
;
CDS_LIB"standard"
BODY_TYPE"PLUMBING"
HDL_TAP"TRUE";
"B \NAC \NWC"1;
"S \NAC"
BN"6"130;
%"TAP"
"1","(3400,775)","0","standard","I459";
;
CDS_LIB"standard"
BODY_TYPE"PLUMBING"
HDL_TAP"TRUE";
"B \NAC \NWC"1;
"S \NAC"
BN"5"131;
%"TAP"
"1","(3400,725)","0","standard","I460";
;
CDS_LIB"standard"
BODY_TYPE"PLUMBING"
HDL_TAP"TRUE";
"B \NAC \NWC"1;
"S \NAC"
BN"4"132;
%"TAP"
"1","(3400,875)","0","standard","I461";
;
CDS_LIB"standard"
BODY_TYPE"PLUMBING"
HDL_TAP"TRUE";
"B \NAC \NWC"1;
"S \NAC"
BN"7"129;
%"TAP"
"1","(3400,925)","0","standard","I462";
;
CDS_LIB"standard"
BODY_TYPE"PLUMBING"
HDL_TAP"TRUE";
"B \NAC \NWC"1;
"S \NAC"
BN"8"128;
%"TAP"
"1","(3400,1075)","0","standard","I463";
;
CDS_LIB"standard"
BODY_TYPE"PLUMBING"
HDL_TAP"TRUE";
"B \NAC \NWC"1;
"S \NAC"
BN"11"125;
%"TAP"
"1","(3400,1025)","0","standard","I464";
;
CDS_LIB"standard"
BODY_TYPE"PLUMBING"
HDL_TAP"TRUE";
"B \NAC \NWC"1;
"S \NAC"
BN"10"126;
%"TAP"
"1","(3400,975)","0","standard","I465";
;
CDS_LIB"standard"
BODY_TYPE"PLUMBING"
HDL_TAP"TRUE";
"B \NAC \NWC"1;
"S \NAC"
BN"9"127;
%"TAP"
"1","(3400,1175)","0","standard","I466";
;
CDS_LIB"standard"
BODY_TYPE"PLUMBING"
HDL_TAP"TRUE";
"B \NAC \NWC"1;
"S \NAC"
BN"13"123;
%"TAP"
"1","(3400,1125)","0","standard","I467";
;
CDS_LIB"standard"
BODY_TYPE"PLUMBING"
HDL_TAP"TRUE";
"B \NAC \NWC"1;
"S \NAC"
BN"12"124;
%"TAP"
"1","(3400,1225)","0","standard","I468";
;
CDS_LIB"standard"
BODY_TYPE"PLUMBING"
HDL_TAP"TRUE";
"B \NAC \NWC"1;
"S \NAC"
BN"14"122;
%"TAP"
"1","(3400,1275)","0","standard","I469";
;
CDS_LIB"standard"
BODY_TYPE"PLUMBING"
HDL_TAP"TRUE";
"B \NAC \NWC"1;
"S \NAC"
BN"15"121;
%"TAP"
"1","(3400,-75)","0","standard","I472";
;
CDS_LIB"standard"
BODY_TYPE"PLUMBING"
HDL_TAP"TRUE";
"B \NAC \NWC"2;
"S \NAC"
BN"5"115;
%"TAP"
"1","(3400,-25)","0","standard","I473";
;
CDS_LIB"standard"
BODY_TYPE"PLUMBING"
HDL_TAP"TRUE";
"B \NAC \NWC"2;
"S \NAC"
BN"6"114;
%"TAP"
"1","(3400,3950)","0","standard","I476";
;
CDS_LIB"standard"
BODY_TYPE"PLUMBING"
HDL_TAP"TRUE";
"B \NAC \NWC"5;
"S \NAC"
BN"13"59;
%"TAP"
"1","(3400,4050)","0","standard","I477";
;
CDS_LIB"standard"
BODY_TYPE"PLUMBING"
HDL_TAP"TRUE";
"B \NAC \NWC"5;
"S \NAC"
BN"15"57;
%"TAP"
"1","(3400,4000)","0","standard","I478";
;
CDS_LIB"standard"
BODY_TYPE"PLUMBING"
HDL_TAP"TRUE";
"B \NAC \NWC"5;
"S \NAC"
BN"14"58;
%"TAP"
"1","(3400,3800)","0","standard","I479";
;
CDS_LIB"standard"
BODY_TYPE"PLUMBING"
HDL_TAP"TRUE";
"B \NAC \NWC"5;
"S \NAC"
BN"10"62;
%"TAP"
"1","(3400,3900)","0","standard","I480";
;
CDS_LIB"standard"
BODY_TYPE"PLUMBING"
HDL_TAP"TRUE";
"B \NAC \NWC"5;
"S \NAC"
BN"12"60;
%"TAP"
"1","(3400,3850)","0","standard","I481";
;
CDS_LIB"standard"
BODY_TYPE"PLUMBING"
HDL_TAP"TRUE";
"B \NAC \NWC"5;
"S \NAC"
BN"11"61;
%"TAP"
"1","(3400,3750)","0","standard","I482";
;
CDS_LIB"standard"
BODY_TYPE"PLUMBING"
HDL_TAP"TRUE";
"B \NAC \NWC"5;
"S \NAC"
BN"9"63;
%"TAP"
"1","(3400,3700)","0","standard","I483";
;
CDS_LIB"standard"
BODY_TYPE"PLUMBING"
HDL_TAP"TRUE";
"B \NAC \NWC"5;
"S \NAC"
BN"8"64;
%"TAP"
"1","(3400,3600)","0","standard","I484";
;
CDS_LIB"standard"
BODY_TYPE"PLUMBING"
HDL_TAP"TRUE";
"B \NAC \NWC"5;
"S \NAC"
BN"6"66;
%"TAP"
"1","(3400,3550)","0","standard","I485";
;
CDS_LIB"standard"
BODY_TYPE"PLUMBING"
HDL_TAP"TRUE";
"B \NAC \NWC"5;
"S \NAC"
BN"5"67;
%"TAP"
"1","(3400,3650)","0","standard","I486";
;
CDS_LIB"standard"
BODY_TYPE"PLUMBING"
HDL_TAP"TRUE";
"B \NAC \NWC"5;
"S \NAC"
BN"7"65;
%"TAP"
"1","(3400,3500)","0","standard","I487";
;
CDS_LIB"standard"
BODY_TYPE"PLUMBING"
HDL_TAP"TRUE";
"B \NAC \NWC"5;
"S \NAC"
BN"4"68;
%"TAP"
"1","(3400,3450)","0","standard","I488";
;
CDS_LIB"standard"
BODY_TYPE"PLUMBING"
HDL_TAP"TRUE";
"B \NAC \NWC"5;
"S \NAC"
BN"3"69;
%"TAP"
"1","(3400,3300)","0","standard","I489";
;
CDS_LIB"standard"
BODY_TYPE"PLUMBING"
HDL_TAP"TRUE";
"B \NAC \NWC"5;
"S \NAC"
BN"0"72;
%"TAP"
"1","(3400,3350)","0","standard","I490";
;
CDS_LIB"standard"
BODY_TYPE"PLUMBING"
HDL_TAP"TRUE";
"B \NAC \NWC"5;
"S \NAC"
BN"1"71;
%"TAP"
"1","(3400,3400)","0","standard","I491";
;
CDS_LIB"standard"
BODY_TYPE"PLUMBING"
HDL_TAP"TRUE";
"B \NAC \NWC"5;
"S \NAC"
BN"2"70;
%"TAP"
"1","(3400,3200)","0","standard","I492";
;
CDS_LIB"standard"
BODY_TYPE"PLUMBING"
HDL_TAP"TRUE";
"B \NAC \NWC"6;
"S \NAC"
BN"15"41;
%"TAP"
"1","(3400,3050)","0","standard","I493";
;
CDS_LIB"standard"
BODY_TYPE"PLUMBING"
HDL_TAP"TRUE";
"B \NAC \NWC"6;
"S \NAC"
BN"12"44;
%"TAP"
"1","(3400,3100)","0","standard","I494";
;
CDS_LIB"standard"
BODY_TYPE"PLUMBING"
HDL_TAP"TRUE";
"B \NAC \NWC"6;
"S \NAC"
BN"13"43;
%"TAP"
"1","(3400,3150)","0","standard","I495";
;
CDS_LIB"standard"
BODY_TYPE"PLUMBING"
HDL_TAP"TRUE";
"B \NAC \NWC"6;
"S \NAC"
BN"14"42;
%"TAP"
"1","(3400,2950)","0","standard","I496";
;
CDS_LIB"standard"
BODY_TYPE"PLUMBING"
HDL_TAP"TRUE";
"B \NAC \NWC"6;
"S \NAC"
BN"10"46;
%"TAP"
"1","(3400,3000)","0","standard","I497";
;
CDS_LIB"standard"
BODY_TYPE"PLUMBING"
HDL_TAP"TRUE";
"B \NAC \NWC"6;
"S \NAC"
BN"11"45;
%"TAP"
"1","(3400,2800)","0","standard","I498";
;
CDS_LIB"standard"
BODY_TYPE"PLUMBING"
HDL_TAP"TRUE";
"B \NAC \NWC"6;
"S \NAC"
BN"7"49;
%"TAP"
"1","(3400,2850)","0","standard","I499";
;
CDS_LIB"standard"
BODY_TYPE"PLUMBING"
HDL_TAP"TRUE";
"B \NAC \NWC"6;
"S \NAC"
BN"8"48;
%"TAP"
"1","(3400,2900)","0","standard","I500";
;
CDS_LIB"standard"
BODY_TYPE"PLUMBING"
HDL_TAP"TRUE";
"B \NAC \NWC"6;
"S \NAC"
BN"9"47;
%"TAP"
"1","(3400,2650)","0","standard","I501";
;
CDS_LIB"standard"
BODY_TYPE"PLUMBING"
HDL_TAP"TRUE";
"B \NAC \NWC"6;
"S \NAC"
BN"4"52;
%"TAP"
"1","(3400,2750)","0","standard","I502";
;
CDS_LIB"standard"
BODY_TYPE"PLUMBING"
HDL_TAP"TRUE";
"B \NAC \NWC"6;
"S \NAC"
BN"6"50;
%"TAP"
"1","(3400,2700)","0","standard","I503";
;
CDS_LIB"standard"
BODY_TYPE"PLUMBING"
HDL_TAP"TRUE";
"B \NAC \NWC"6;
"S \NAC"
BN"5"51;
%"TAP"
"1","(3400,2600)","0","standard","I504";
;
CDS_LIB"standard"
BODY_TYPE"PLUMBING"
HDL_TAP"TRUE";
"B \NAC \NWC"6;
"S \NAC"
BN"3"53;
%"TAP"
"1","(3400,2550)","0","standard","I505";
;
CDS_LIB"standard"
BODY_TYPE"PLUMBING"
HDL_TAP"TRUE";
"B \NAC \NWC"6;
"S \NAC"
BN"2"54;
%"TAP"
"1","(3400,2500)","0","standard","I506";
;
CDS_LIB"standard"
BODY_TYPE"PLUMBING"
HDL_TAP"TRUE";
"B \NAC \NWC"6;
"S \NAC"
BN"1"55;
%"TAP"
"1","(3400,2450)","0","standard","I507";
;
CDS_LIB"standard"
BODY_TYPE"PLUMBING"
HDL_TAP"TRUE";
"B \NAC \NWC"6;
"S \NAC"
BN"0"56;
%"SOCKET4677_AZIF0045P001C01CS"
"18","(1675,475)","0","pure_quanta","I69";
;
PART_NUMBER"DGA^7000023"
VALUE"SOCKET4677_AZIF0045-P001C01CS"
MATERIAL"IO"
PART_TYPE"SMLF"
$LOCATION"U1"
CDS_LMAN_SYM_OUTLINE"-1050,950,1050,-950"
NEEDS_NO_SIZE"TRUE"
CDS_LIB"pure_quanta"
CDS_LOCATION"U1"
$SEC"18"
CDS_SEC"18";
"PE1_TX_DP0"
$PN"CR15"136;
"PE1_TX_DP1"
$PN"CM14"135;
"PE1_TX_DP2"
$PN"CL15"134;
"PE1_TX_DP3"
$PN"CH14"133;
"PE1_TX_DP4"
$PN"CG15"132;
"PE1_TX_DP5"
$PN"CD14"131;
"PE1_TX_DP6"
$PN"CC15"130;
"PE1_TX_DP7"
$PN"BY14"129;
"PE1_TX_DP8"
$PN"BW15"128;
"PE1_TX_DP9"
$PN"BT14"127;
"PE1_TX_DP10"
$PN"BR15"126;
"PE1_TX_DP11"
$PN"BM14"125;
"PE1_TX_DP12"
$PN"BL15"124;
"PE1_TX_DP13"
$PN"BH14"123;
"PE1_TX_DP14"
$PN"BG15"122;
"PE1_TX_DP15"
$PN"BD14"121;
"PE1_TX_DN0"
$PN"CP14"120;
"PE1_TX_DN1"
$PN"CN13"119;
"PE1_TX_DN2"
$PN"CK14"118;
"PE1_TX_DN3"
$PN"CJ13"117;
"PE1_TX_DN4"
$PN"CF14"116;
"PE1_TX_DN5"
$PN"CE13"115;
"PE1_TX_DN6"
$PN"CB14"114;
"PE1_TX_DN7"
$PN"CA13"113;
"PE1_TX_DN8"
$PN"BV14"112;
"PE1_TX_DN9"
$PN"BU13"111;
"PE1_TX_DN10"
$PN"BP14"110;
"PE1_TX_DN11"
$PN"BN13"109;
"PE1_TX_DN12"
$PN"BK14"108;
"PE1_TX_DN13"
$PN"BJ13"107;
"PE1_TX_DN14"
$PN"BF14"106;
"PE1_TX_DN15"
$PN"BE13"105;
"PE1_RX_DP0"
$PN"CN9"104;
"PE1_RX_DP1"
$PN"CM10"103;
"PE1_RX_DP2"
$PN"CJ9"102;
"PE1_RX_DP3"
$PN"CH10"101;
"PE1_RX_DP4"
$PN"CE9"100;
"PE1_RX_DP5"
$PN"CD10"99;
"PE1_RX_DP6"
$PN"CA9"98;
"PE1_RX_DP7"
$PN"BY10"97;
"PE1_RX_DP8"
$PN"BU9"96;
"PE1_RX_DP9"
$PN"BT10"95;
"PE1_RX_DP10"
$PN"BN9"94;
"PE1_RX_DP11"
$PN"BM10"93;
"PE1_RX_DP12"
$PN"BJ9"92;
"PE1_RX_DP13"
$PN"BH10"91;
"PE1_RX_DP14"
$PN"BE9"90;
"PE1_RX_DP15"
$PN"BD10"89;
"PE1_RX_DN0"
$PN"CP10"88;
"PE1_RX_DN1"
$PN"CL11"87;
"PE1_RX_DN2"
$PN"CK10"86;
"PE1_RX_DN3"
$PN"CG11"85;
"PE1_RX_DN4"
$PN"CF10"84;
"PE1_RX_DN5"
$PN"CC11"83;
"PE1_RX_DN6"
$PN"CB10"82;
"PE1_RX_DN7"
$PN"BW11"81;
"PE1_RX_DN8"
$PN"BV10"80;
"PE1_RX_DN9"
$PN"BR11"79;
"PE1_RX_DN10"
$PN"BP10"78;
"PE1_RX_DN11"
$PN"BL11"77;
"PE1_RX_DN12"
$PN"BK10"76;
"PE1_RX_DN13"
$PN"BG11"75;
"PE1_RX_DN14"
$PN"BF10"74;
"PE1_RX_DN15"
$PN"BC11"73;
%"SOCKET4677_AZIF0045P001C01CS"
"17","(1675,3250)","0","pure_quanta","I80";
;
PART_NUMBER"DGA^7000023"
VALUE"SOCKET4677_AZIF0045-P001C01CS"
MATERIAL"IO"
PART_TYPE"SMLF"
$LOCATION"U1"
CDS_LMAN_SYM_OUTLINE"-1050,950,1050,-950"
NEEDS_NO_SIZE"TRUE"
CDS_LIB"pure_quanta"
CDS_LOCATION"U1"
$SEC"17"
CDS_SEC"17";
"PE0_TX_DP0"
$PN"M14"72;
"PE0_TX_DP1"
$PN"R15"71;
"PE0_TX_DP2"
$PN"T14"70;
"PE0_TX_DP3"
$PN"W15"69;
"PE0_TX_DP4"
$PN"Y14"68;
"PE0_TX_DP5"
$PN"AC15"67;
"PE0_TX_DP6"
$PN"AD14"66;
"PE0_TX_DP7"
$PN"AG15"65;
"PE0_TX_DP8"
$PN"AH14"64;
"PE0_TX_DP9"
$PN"AL15"63;
"PE0_TX_DP10"
$PN"AM14"62;
"PE0_TX_DP11"
$PN"AR15"61;
"PE0_TX_DP12"
$PN"AT14"60;
"PE0_TX_DP13"
$PN"AW15"59;
"PE0_TX_DP14"
$PN"AY14"58;
"PE0_TX_DP15"
$PN"BC15"57;
"PE0_TX_DN0"
$PN"N13"56;
"PE0_TX_DN1"
$PN"P14"55;
"PE0_TX_DN2"
$PN"U13"54;
"PE0_TX_DN3"
$PN"V14"53;
"PE0_TX_DN4"
$PN"AA13"52;
"PE0_TX_DN5"
$PN"AB14"51;
"PE0_TX_DN6"
$PN"AE13"50;
"PE0_TX_DN7"
$PN"AF14"49;
"PE0_TX_DN8"
$PN"AJ13"48;
"PE0_TX_DN9"
$PN"AK14"47;
"PE0_TX_DN10"
$PN"AN13"46;
"PE0_TX_DN11"
$PN"AP14"45;
"PE0_TX_DN12"
$PN"AU13"44;
"PE0_TX_DN13"
$PN"AV14"43;
"PE0_TX_DN14"
$PN"BA13"42;
"PE0_TX_DN15"
$PN"BB14"41;
"PE0_RX_DP0"
$PN"L11"40;
"PE0_RX_DP1"
$PN"N9"39;
"PE0_RX_DP2"
$PN"R11"38;
"PE0_RX_DP3"
$PN"U9"37;
"PE0_RX_DP4"
$PN"W11"36;
"PE0_RX_DP5"
$PN"Y10"35;
"PE0_RX_DP6"
$PN"AC11"34;
"PE0_RX_DP7"
$PN"AD10"33;
"PE0_RX_DP8"
$PN"AG11"32;
"PE0_RX_DP9"
$PN"AH10"31;
"PE0_RX_DP10"
$PN"AL11"30;
"PE0_RX_DP11"
$PN"AN9"29;
"PE0_RX_DP12"
$PN"AR11"28;
"PE0_RX_DP13"
$PN"AT10"27;
"PE0_RX_DP14"
$PN"AW11"26;
"PE0_RX_DP15"
$PN"AY10"25;
"PE0_RX_DN0"
$PN"K10"24;
"PE0_RX_DN1"
$PN"M10"23;
"PE0_RX_DN2"
$PN"P10"22;
"PE0_RX_DN3"
$PN"T10"21;
"PE0_RX_DN4"
$PN"V10"20;
"PE0_RX_DN5"
$PN"AA9"19;
"PE0_RX_DN6"
$PN"AB10"18;
"PE0_RX_DN7"
$PN"AE9"17;
"PE0_RX_DN8"
$PN"AF10"16;
"PE0_RX_DN9"
$PN"AJ9"15;
"PE0_RX_DN10"
$PN"AK10"14;
"PE0_RX_DN11"
$PN"AM10"13;
"PE0_RX_DN12"
$PN"AP10"12;
"PE0_RX_DN13"
$PN"AU9"11;
"PE0_RX_DN14"
$PN"AV10"10;
"PE0_RX_DN15"
$PN"BA9"9;
END.
